(kicad_pcb
	(version 20260206)
	(generator "pcbnew")
	(generator_version "10.0")
	(general
		(thickness 1.6)
		(legacy_teardrops no)
	)
	(paper "A4")
	(title_block
		(title "04192023_DAF0TMB3IC0_F0TG_MB_C_brd_V02_OCP.brd")
		(comment 1 "Grand Teton / footprints 2977-2982 of 8354")
	)
	(layers
		(0 "F.Cu" signal "TOP")
		(4 "In1.Cu" signal "GND")
		(6 "In2.Cu" signal "IN1")
		(8 "In3.Cu" signal "GND1")
		(10 "In4.Cu" signal "IN2")
		(12 "In5.Cu" signal "GND2")
		(14 "In6.Cu" signal "IN3")
		(16 "In7.Cu" signal "GND3")
		(18 "In8.Cu" signal "VCC")
		(20 "In9.Cu" signal "VCC1")
		(22 "In10.Cu" signal "GND4")
		(24 "In11.Cu" signal "IN4")
		(26 "In12.Cu" signal "GND5")
		(28 "In13.Cu" signal "IN5")
		(30 "In14.Cu" signal "GND6")
		(32 "In15.Cu" signal "IN6")
		(34 "In16.Cu" signal "GND7")
		(2 "B.Cu" signal "BOTTOM")
		(9 "F.Adhes" user "F.Adhesive")
		(11 "B.Adhes" user "B.Adhesive")
		(13 "F.Paste" user "Package Geometry/Pastemask Top")
		(15 "B.Paste" user "Package Geometry/Pastemask Bottom")
		(5 "F.SilkS" user "Ref Des/Silkscreen Top")
		(7 "B.SilkS" user "Ref Des/Silkscreen Bottom")
		(1 "F.Mask" user "Board Geometry/Soldermask Top")
		(3 "B.Mask" user "Board Geometry/Soldermask Bottom")
		(17 "Dwgs.User" user "User.Drawings")
		(19 "Cmts.User" user "User.Comments")
		(21 "Eco1.User" user "User.Eco1")
		(23 "Eco2.User" user "User.Eco2")
		(25 "Edge.Cuts" user "Board Geometry/Outline")
		(27 "Margin" user)
		(31 "F.CrtYd" user "Package Geometry/Place Bound Top")
		(29 "B.CrtYd" user "Package Geometry/Place Bound Bottom")
		(35 "F.Fab" user "Ref Des/Assembly Top")
		(33 "B.Fab" user "Ref Des/Assembly Bottom")
	)
	(footprint ""
		(layer "F.Cu")
		(at 256.442972 -101.74351 -90)
		(property "Reference" "C1514"
			(at 0 0 270)
			(layer "F.SilkS")
			(hide yes)
			(effects
				(font
					(size 1.27 1.27)
				)
			)
		)
		(property "Value" ""
			(at 0 0 270)
			(layer "F.Fab")
			(effects
				(font
					(size 1.27 1.27)
				)
			)
		)
		(duplicate_pad_numbers_are_jumpers no)
		(fp_line
			(start -0.7874 0.4064)
			(end -0.7874 -0.4064)
			(stroke
				(width 0.1524)
				(type default)
			)
			(layer "F.SilkS")
		)
		(fp_line
			(start 0.7874 0.4064)
			(end -0.7874 0.4064)
			(stroke
				(width 0.1524)
				(type default)
			)
			(layer "F.SilkS")
		)
		(fp_line
			(start -0.7874 -0.4064)
			(end 0.7874 -0.4064)
			(stroke
				(width 0.1524)
				(type default)
			)
			(layer "F.SilkS")
		)
		(fp_line
			(start 0.7874 -0.4064)
			(end 0.7874 0.4064)
			(stroke
				(width 0.1524)
				(type default)
			)
			(layer "F.SilkS")
		)
		(fp_line
			(start -0.67945 0.3048)
			(end -0.67945 -0.305054)
			(stroke
				(width 0.1)
				(type default)
			)
			(layer "F.Fab")
		)
		(fp_line
			(start -0.12065 0.3048)
			(end -0.67945 0.3048)
			(stroke
				(width 0.1)
				(type default)
			)
			(layer "F.Fab")
		)
		(fp_line
			(start 0.120396 0.3048)
			(end 0.120396 0.2794)
			(stroke
				(width 0.1)
				(type default)
			)
			(layer "F.Fab")
		)
		(fp_line
			(start 0.67945 0.3048)
			(end 0.120396 0.3048)
			(stroke
				(width 0.1)
				(type default)
			)
			(layer "F.Fab")
		)
		(fp_line
			(start -0.12065 0.2794)
			(end -0.12065 0.3048)
			(stroke
				(width 0.1)
				(type default)
			)
			(layer "F.Fab")
		)
		(fp_line
			(start 0.120396 0.2794)
			(end -0.12065 0.2794)
			(stroke
				(width 0.1)
				(type default)
			)
			(layer "F.Fab")
		)
		(fp_line
			(start -0.12065 -0.2794)
			(end 0.12065 -0.2794)
			(stroke
				(width 0.1)
				(type default)
			)
			(layer "F.Fab")
		)
		(fp_line
			(start 0.12065 -0.2794)
			(end 0.12065 -0.3048)
			(stroke
				(width 0.1)
				(type default)
			)
			(layer "F.Fab")
		)
		(fp_line
			(start 0.12065 -0.3048)
			(end 0.67945 -0.3048)
			(stroke
				(width 0.1)
				(type default)
			)
			(layer "F.Fab")
		)
		(fp_line
			(start 0.67945 -0.3048)
			(end 0.67945 0.3048)
			(stroke
				(width 0.1)
				(type default)
			)
			(layer "F.Fab")
		)
		(fp_line
			(start -0.67945 -0.305054)
			(end -0.12065 -0.305054)
			(stroke
				(width 0.1)
				(type default)
			)
			(layer "F.Fab")
		)
		(fp_line
			(start -0.12065 -0.305054)
			(end -0.12065 -0.2794)
			(stroke
				(width 0.1)
				(type default)
			)
			(layer "F.Fab")
		)
		(pad "1" smd circle
			(at -0.40005 0 270)
			(size 0 0)
			(layers "F.Cu" "F.Mask" "F.Paste")
			(net "PVDD18_S5_P0")
		)
		(pad "2" smd circle
			(at 0.40005 0 270)
			(size 0 0)
			(layers "F.Cu" "F.Mask" "F.Paste")
			(net "GND")
		)
	)
	(footprint ""
		(layer "F.Cu")
		(at 125.270514 -159.980884)
		(property "Reference" "PR208"
			(at 0 0 0)
			(layer "F.SilkS")
			(hide yes)
			(effects
				(font
					(size 1.27 1.27)
				)
			)
		)
		(property "Value" ""
			(at 0 0 0)
			(layer "F.Fab")
			(effects
				(font
					(size 1.27 1.27)
				)
			)
		)
		(duplicate_pad_numbers_are_jumpers no)
		(fp_line
			(start -0.7874 -0.4064)
			(end 0.7874 -0.4064)
			(stroke
				(width 0.1524)
				(type default)
			)
			(layer "F.SilkS")
		)
		(fp_line
			(start -0.7874 0.4064)
			(end -0.7874 -0.4064)
			(stroke
				(width 0.1524)
				(type default)
			)
			(layer "F.SilkS")
		)
		(fp_line
			(start 0.7874 -0.4064)
			(end 0.7874 0.4064)
			(stroke
				(width 0.1524)
				(type default)
			)
			(layer "F.SilkS")
		)
		(fp_line
			(start 0.7874 0.4064)
			(end -0.7874 0.4064)
			(stroke
				(width 0.1524)
				(type default)
			)
			(layer "F.SilkS")
		)
		(fp_line
			(start -0.67945 -0.305054)
			(end -0.12065 -0.305054)
			(stroke
				(width 0.1)
				(type default)
			)
			(layer "F.Fab")
		)
		(fp_line
			(start -0.67945 0.3048)
			(end -0.67945 -0.305054)
			(stroke
				(width 0.1)
				(type default)
			)
			(layer "F.Fab")
		)
		(fp_line
			(start -0.12065 -0.305054)
			(end -0.12065 -0.2794)
			(stroke
				(width 0.1)
				(type default)
			)
			(layer "F.Fab")
		)
		(fp_line
			(start -0.12065 -0.2794)
			(end 0.12065 -0.2794)
			(stroke
				(width 0.1)
				(type default)
			)
			(layer "F.Fab")
		)
		(fp_line
			(start -0.12065 0.2794)
			(end -0.12065 0.3048)
			(stroke
				(width 0.1)
				(type default)
			)
			(layer "F.Fab")
		)
		(fp_line
			(start -0.12065 0.3048)
			(end -0.67945 0.3048)
			(stroke
				(width 0.1)
				(type default)
			)
			(layer "F.Fab")
		)
		(fp_line
			(start 0.120396 0.2794)
			(end -0.12065 0.2794)
			(stroke
				(width 0.1)
				(type default)
			)
			(layer "F.Fab")
		)
		(fp_line
			(start 0.120396 0.3048)
			(end 0.120396 0.2794)
			(stroke
				(width 0.1)
				(type default)
			)
			(layer "F.Fab")
		)
		(fp_line
			(start 0.12065 -0.3048)
			(end 0.67945 -0.3048)
			(stroke
				(width 0.1)
				(type default)
			)
			(layer "F.Fab")
		)
		(fp_line
			(start 0.12065 -0.2794)
			(end 0.12065 -0.3048)
			(stroke
				(width 0.1)
				(type default)
			)
			(layer "F.Fab")
		)
		(fp_line
			(start 0.67945 -0.3048)
			(end 0.67945 0.3048)
			(stroke
				(width 0.1)
				(type default)
			)
			(layer "F.Fab")
		)
		(fp_line
			(start 0.67945 0.3048)
			(end 0.120396 0.3048)
			(stroke
				(width 0.1)
				(type default)
			)
			(layer "F.Fab")
		)
		(pad "1" smd circle
			(at -0.40005 0)
			(size 0 0)
			(layers "F.Cu" "F.Mask" "F.Paste")
			(net "GND")
		)
		(pad "2" smd circle
			(at 0.40005 0)
			(size 0 0)
			(layers "F.Cu" "F.Mask" "F.Paste")
			(net "PVDDCR_SOC_P1_LSET2")
		)
	)
	(footprint ""
		(layer "F.Cu")
		(at 211.992464 -26.868374 -90)
		(property "Reference" "C1274"
			(at 0 0 270)
			(layer "F.SilkS")
			(hide yes)
			(effects
				(font
					(size 1.27 1.27)
				)
			)
		)
		(property "Value" ""
			(at 0 0 270)
			(layer "F.Fab")
			(effects
				(font
					(size 1.27 1.27)
				)
			)
		)
		(duplicate_pad_numbers_are_jumpers no)
		(fp_line
			(start -0.7874 0.4064)
			(end -0.7874 -0.4064)
			(stroke
				(width 0.1524)
				(type default)
			)
			(layer "F.SilkS")
		)
		(fp_line
			(start 0.7874 0.4064)
			(end -0.7874 0.4064)
			(stroke
				(width 0.1524)
				(type default)
			)
			(layer "F.SilkS")
		)
		(fp_line
			(start -0.7874 -0.4064)
			(end 0.7874 -0.4064)
			(stroke
				(width 0.1524)
				(type default)
			)
			(layer "F.SilkS")
		)
		(fp_line
			(start 0.7874 -0.4064)
			(end 0.7874 0.4064)
			(stroke
				(width 0.1524)
				(type default)
			)
			(layer "F.SilkS")
		)
		(fp_line
			(start -0.67945 0.3048)
			(end -0.67945 -0.305054)
			(stroke
				(width 0.1)
				(type default)
			)
			(layer "F.Fab")
		)
		(fp_line
			(start -0.12065 0.3048)
			(end -0.67945 0.3048)
			(stroke
				(width 0.1)
				(type default)
			)
			(layer "F.Fab")
		)
		(fp_line
			(start 0.120396 0.3048)
			(end 0.120396 0.2794)
			(stroke
				(width 0.1)
				(type default)
			)
			(layer "F.Fab")
		)
		(fp_line
			(start 0.67945 0.3048)
			(end 0.120396 0.3048)
			(stroke
				(width 0.1)
				(type default)
			)
			(layer "F.Fab")
		)
		(fp_line
			(start -0.12065 0.2794)
			(end -0.12065 0.3048)
			(stroke
				(width 0.1)
				(type default)
			)
			(layer "F.Fab")
		)
		(fp_line
			(start 0.120396 0.2794)
			(end -0.12065 0.2794)
			(stroke
				(width 0.1)
				(type default)
			)
			(layer "F.Fab")
		)
		(fp_line
			(start -0.12065 -0.2794)
			(end 0.12065 -0.2794)
			(stroke
				(width 0.1)
				(type default)
			)
			(layer "F.Fab")
		)
		(fp_line
			(start 0.12065 -0.2794)
			(end 0.12065 -0.3048)
			(stroke
				(width 0.1)
				(type default)
			)
			(layer "F.Fab")
		)
		(fp_line
			(start 0.12065 -0.3048)
			(end 0.67945 -0.3048)
			(stroke
				(width 0.1)
				(type default)
			)
			(layer "F.Fab")
		)
		(fp_line
			(start 0.67945 -0.3048)
			(end 0.67945 0.3048)
			(stroke
				(width 0.1)
				(type default)
			)
			(layer "F.Fab")
		)
		(fp_line
			(start -0.67945 -0.305054)
			(end -0.12065 -0.305054)
			(stroke
				(width 0.1)
				(type default)
			)
			(layer "F.Fab")
		)
		(fp_line
			(start -0.12065 -0.305054)
			(end -0.12065 -0.2794)
			(stroke
				(width 0.1)
				(type default)
			)
			(layer "F.Fab")
		)
		(pad "1" smd circle
			(at -0.40005 0 270)
			(size 0 0)
			(layers "F.Cu" "F.Mask" "F.Paste")
			(net "P3V3_AUX")
		)
		(pad "2" smd circle
			(at 0.40005 0 270)
			(size 0 0)
			(layers "F.Cu" "F.Mask" "F.Paste")
			(net "GND")
		)
	)
	(footprint ""
		(layer "F.Cu")
		(at 325.49338 -394.82268 90)
		(property "Reference" "C505"
			(at 0 0 90)
			(layer "F.SilkS")
			(hide yes)
			(effects
				(font
					(size 1.27 1.27)
				)
			)
		)
		(property "Value" ""
			(at 0 0 90)
			(layer "F.Fab")
			(effects
				(font
					(size 1.27 1.27)
				)
			)
		)
		(duplicate_pad_numbers_are_jumpers no)
		(fp_line
			(start 0.7874 -0.4064)
			(end 0.7874 0.4064)
			(stroke
				(width 0.1524)
				(type default)
			)
			(layer "F.SilkS")
		)
		(fp_line
			(start -0.7874 -0.4064)
			(end 0.7874 -0.4064)
			(stroke
				(width 0.1524)
				(type default)
			)
			(layer "F.SilkS")
		)
		(fp_line
			(start 0.7874 0.4064)
			(end -0.7874 0.4064)
			(stroke
				(width 0.1524)
				(type default)
			)
			(layer "F.SilkS")
		)
		(fp_line
			(start -0.7874 0.4064)
			(end -0.7874 -0.4064)
			(stroke
				(width 0.1524)
				(type default)
			)
			(layer "F.SilkS")
		)
		(fp_line
			(start -0.12065 -0.305054)
			(end -0.12065 -0.2794)
			(stroke
				(width 0.1)
				(type default)
			)
			(layer "F.Fab")
		)
		(fp_line
			(start -0.67945 -0.305054)
			(end -0.12065 -0.305054)
			(stroke
				(width 0.1)
				(type default)
			)
			(layer "F.Fab")
		)
		(fp_line
			(start 0.67945 -0.3048)
			(end 0.67945 0.3048)
			(stroke
				(width 0.1)
				(type default)
			)
			(layer "F.Fab")
		)
		(fp_line
			(start 0.12065 -0.3048)
			(end 0.67945 -0.3048)
			(stroke
				(width 0.1)
				(type default)
			)
			(layer "F.Fab")
		)
		(fp_line
			(start 0.12065 -0.2794)
			(end 0.12065 -0.3048)
			(stroke
				(width 0.1)
				(type default)
			)
			(layer "F.Fab")
		)
		(fp_line
			(start -0.12065 -0.2794)
			(end 0.12065 -0.2794)
			(stroke
				(width 0.1)
				(type default)
			)
			(layer "F.Fab")
		)
		(fp_line
			(start 0.120396 0.2794)
			(end -0.12065 0.2794)
			(stroke
				(width 0.1)
				(type default)
			)
			(layer "F.Fab")
		)
		(fp_line
			(start -0.12065 0.2794)
			(end -0.12065 0.3048)
			(stroke
				(width 0.1)
				(type default)
			)
			(layer "F.Fab")
		)
		(fp_line
			(start 0.67945 0.3048)
			(end 0.120396 0.3048)
			(stroke
				(width 0.1)
				(type default)
			)
			(layer "F.Fab")
		)
		(fp_line
			(start 0.120396 0.3048)
			(end 0.120396 0.2794)
			(stroke
				(width 0.1)
				(type default)
			)
			(layer "F.Fab")
		)
		(fp_line
			(start -0.12065 0.3048)
			(end -0.67945 0.3048)
			(stroke
				(width 0.1)
				(type default)
			)
			(layer "F.Fab")
		)
		(fp_line
			(start -0.67945 0.3048)
			(end -0.67945 -0.305054)
			(stroke
				(width 0.1)
				(type default)
			)
			(layer "F.Fab")
		)
		(pad "1" smd circle
			(at -0.40005 0 90)
			(size 0 0)
			(layers "F.Cu" "F.Mask" "F.Paste")
			(net "P1V8_CPU0_RT0_1A")
		)
		(pad "2" smd circle
			(at 0.40005 0 90)
			(size 0 0)
			(layers "F.Cu" "F.Mask" "F.Paste")
			(net "GND")
		)
	)
	(footprint ""
		(layer "F.Cu")
		(at 95.39097 -61.87821)
		(property "Reference" "PR3812"
			(at 0 0 0)
			(layer "F.SilkS")
			(hide yes)
			(effects
				(font
					(size 1.27 1.27)
				)
			)
		)
		(property "Value" ""
			(at 0 0 0)
			(layer "F.Fab")
			(effects
				(font
					(size 1.27 1.27)
				)
			)
		)
		(duplicate_pad_numbers_are_jumpers no)
		(fp_line
			(start -0.7874 -0.4064)
			(end 0.7874 -0.4064)
			(stroke
				(width 0.1524)
				(type default)
			)
			(layer "F.SilkS")
		)
		(fp_line
			(start -0.7874 0.4064)
			(end -0.7874 -0.4064)
			(stroke
				(width 0.1524)
				(type default)
			)
			(layer "F.SilkS")
		)
		(fp_line
			(start 0.7874 -0.4064)
			(end 0.7874 0.4064)
			(stroke
				(width 0.1524)
				(type default)
			)
			(layer "F.SilkS")
		)
		(fp_line
			(start 0.7874 0.4064)
			(end -0.7874 0.4064)
			(stroke
				(width 0.1524)
				(type default)
			)
			(layer "F.SilkS")
		)
		(fp_line
			(start -0.67945 -0.305054)
			(end -0.12065 -0.305054)
			(stroke
				(width 0.1)
				(type default)
			)
			(layer "F.Fab")
		)
		(fp_line
			(start -0.67945 0.3048)
			(end -0.67945 -0.305054)
			(stroke
				(width 0.1)
				(type default)
			)
			(layer "F.Fab")
		)
		(fp_line
			(start -0.12065 -0.305054)
			(end -0.12065 -0.2794)
			(stroke
				(width 0.1)
				(type default)
			)
			(layer "F.Fab")
		)
		(fp_line
			(start -0.12065 -0.2794)
			(end 0.12065 -0.2794)
			(stroke
				(width 0.1)
				(type default)
			)
			(layer "F.Fab")
		)
		(fp_line
			(start -0.12065 0.2794)
			(end -0.12065 0.3048)
			(stroke
				(width 0.1)
				(type default)
			)
			(layer "F.Fab")
		)
		(fp_line
			(start -0.12065 0.3048)
			(end -0.67945 0.3048)
			(stroke
				(width 0.1)
				(type default)
			)
			(layer "F.Fab")
		)
		(fp_line
			(start 0.120396 0.2794)
			(end -0.12065 0.2794)
			(stroke
				(width 0.1)
				(type default)
			)
			(layer "F.Fab")
		)
		(fp_line
			(start 0.120396 0.3048)
			(end 0.120396 0.2794)
			(stroke
				(width 0.1)
				(type default)
			)
			(layer "F.Fab")
		)
		(fp_line
			(start 0.12065 -0.3048)
			(end 0.67945 -0.3048)
			(stroke
				(width 0.1)
				(type default)
			)
			(layer "F.Fab")
		)
		(fp_line
			(start 0.12065 -0.2794)
			(end 0.12065 -0.3048)
			(stroke
				(width 0.1)
				(type default)
			)
			(layer "F.Fab")
		)
		(fp_line
			(start 0.67945 -0.3048)
			(end 0.67945 0.3048)
			(stroke
				(width 0.1)
				(type default)
			)
			(layer "F.Fab")
		)
		(fp_line
			(start 0.67945 0.3048)
			(end 0.120396 0.3048)
			(stroke
				(width 0.1)
				(type default)
			)
			(layer "F.Fab")
		)
		(pad "1" smd circle
			(at -0.40005 0)
			(size 0 0)
			(layers "F.Cu" "F.Mask" "F.Paste")
			(net "P3V3_OCP_OV_2")
		)
		(pad "2" smd circle
			(at 0.40005 0)
			(size 0 0)
			(layers "F.Cu" "F.Mask" "F.Paste")
			(net "GND")
		)
	)
	(footprint ""
		(layer "F.Cu")
		(at 427.269656 -396.145004 180)
		(property "Reference" "R1050"
			(at 0 0 180)
			(layer "F.SilkS")
			(hide yes)
			(effects
				(font
					(size 1.27 1.27)
				)
			)
		)
		(property "Value" ""
			(at 0 0 180)
			(layer "F.Fab")
			(effects
				(font
					(size 1.27 1.27)
				)
			)
		)
		(duplicate_pad_numbers_are_jumpers no)
		(fp_line
			(start 0.7874 0.4064)
			(end -0.7874 0.4064)
			(stroke
				(width 0.1524)
				(type default)
			)
			(layer "F.SilkS")
		)
		(fp_line
			(start 0.7874 -0.4064)
			(end 0.7874 0.4064)
			(stroke
				(width 0.1524)
				(type default)
			)
			(layer "F.SilkS")
		)
		(fp_line
			(start -0.7874 0.4064)
			(end -0.7874 -0.4064)
			(stroke
				(width 0.1524)
				(type default)
			)
			(layer "F.SilkS")
		)
		(fp_line
			(start -0.7874 -0.4064)
			(end 0.7874 -0.4064)
			(stroke
				(width 0.1524)
				(type default)
			)
			(layer "F.SilkS")
		)
		(fp_line
			(start 0.67945 0.3048)
			(end 0.120396 0.3048)
			(stroke
				(width 0.1)
				(type default)
			)
			(layer "F.Fab")
		)
		(fp_line
			(start 0.67945 -0.3048)
			(end 0.67945 0.3048)
			(stroke
				(width 0.1)
				(type default)
			)
			(layer "F.Fab")
		)
		(fp_line
			(start 0.12065 -0.2794)
			(end 0.12065 -0.3048)
			(stroke
				(width 0.1)
				(type default)
			)
			(layer "F.Fab")
		)
		(fp_line
			(start 0.12065 -0.3048)
			(end 0.67945 -0.3048)
			(stroke
				(width 0.1)
				(type default)
			)
			(layer "F.Fab")
		)
		(fp_line
			(start 0.120396 0.3048)
			(end 0.120396 0.2794)
			(stroke
				(width 0.1)
				(type default)
			)
			(layer "F.Fab")
		)
		(fp_line
			(start 0.120396 0.2794)
			(end -0.12065 0.2794)
			(stroke
				(width 0.1)
				(type default)
			)
			(layer "F.Fab")
		)
		(fp_line
			(start -0.12065 0.3048)
			(end -0.67945 0.3048)
			(stroke
				(width 0.1)
				(type default)
			)
			(layer "F.Fab")
		)
		(fp_line
			(start -0.12065 0.2794)
			(end -0.12065 0.3048)
			(stroke
				(width 0.1)
				(type default)
			)
			(layer "F.Fab")
		)
		(fp_line
			(start -0.12065 -0.2794)
			(end 0.12065 -0.2794)
			(stroke
				(width 0.1)
				(type default)
			)
			(layer "F.Fab")
		)
		(fp_line
			(start -0.12065 -0.305054)
			(end -0.12065 -0.2794)
			(stroke
				(width 0.1)
				(type default)
			)
			(layer "F.Fab")
		)
		(fp_line
			(start -0.67945 0.3048)
			(end -0.67945 -0.305054)
			(stroke
				(width 0.1)
				(type default)
			)
			(layer "F.Fab")
		)
		(fp_line
			(start -0.67945 -0.305054)
			(end -0.12065 -0.305054)
			(stroke
				(width 0.1)
				(type default)
			)
			(layer "F.Fab")
		)
		(pad "1" smd rect
			(at -0.40005 0)
			(size 0.4572 0.508)
			(layers "F.Cu" "F.Mask" "F.Paste")
			(net "P1V8_CPU0_RT_1D")
		)
		(pad "2" smd rect
			(at 0.40005 0)
			(size 0.4572 0.508)
			(layers "F.Cu" "F.Mask" "F.Paste")
			(net "P1V8_CPU0_RT2_1A_1D")
		)
	)
)
